(kicad_pcb
	(version 20260206)
	(generator "pcbnew")
	(generator_version "10.0")
	(general
		(thickness 1.6)
		(legacy_teardrops no)
	)
	(paper "A4")
	(title_block
		(title "netronome-mezz — pcbd0082-001_rev01_jul9_a.brd")
		(comment 1 "Open CloudServer (Microsoft) / footprints 678-686 of 714")
	)
	(layers
		(0 "F.Cu" signal "TOP")
		(4 "In1.Cu" signal "02_GND")
		(6 "In2.Cu" signal "03_SIG")
		(8 "In3.Cu" signal "04_SIG")
		(10 "In4.Cu" signal "05_GND")
		(12 "In5.Cu" signal "06_PWR1")
		(14 "In6.Cu" signal "07_SIG")
		(16 "In7.Cu" signal "08_SIG")
		(18 "In8.Cu" signal "09_GND")
		(2 "B.Cu" signal "BOTTOM")
		(9 "F.Adhes" user "F.Adhesive")
		(11 "B.Adhes" user "B.Adhesive")
		(13 "F.Paste" user "Package Geometry/Pastemask Top")
		(15 "B.Paste" user "Package Geometry/Pastemask Bottom")
		(5 "F.SilkS" user "Ref Des/Silkscreen Top")
		(7 "B.SilkS" user "Ref Des/Silkscreen Bottom")
		(1 "F.Mask" user "Board Geometry/Soldermask Top")
		(3 "B.Mask" user "Board Geometry/Soldermask Bottom")
		(17 "Dwgs.User" user "User.Drawings")
		(19 "Cmts.User" user "User.Comments")
		(21 "Eco1.User" user "User.Eco1")
		(23 "Eco2.User" user "User.Eco2")
		(25 "Edge.Cuts" user "Board Geometry/Outline")
		(27 "Margin" user)
		(31 "F.CrtYd" user "Package Geometry/Place Bound Top")
		(29 "B.CrtYd" user "Package Geometry/Place Bound Bottom")
		(35 "F.Fab" user "Ref Des/Assembly Top")
		(33 "B.Fab" user "Ref Des/Assembly Bottom")
		(45 "User.4" user "COMPVAL_TYPE_BOTTOM")
	)
	(footprint ""
		(layer "B.Cu")
		(at 51.737006 9.042019 90)
		(property "Reference" "C102"
			(at 0 0 90)
			(layer "B.SilkS")
			(hide yes)
			(effects
				(font
					(size 1.27 1.27)
				)
				(justify mirror)
			)
		)
		(property "Value" ""
			(at 0 0 90)
			(layer "B.Fab")
			(effects
				(font
					(size 1.27 1.27)
				)
				(justify mirror)
			)
		)
		(duplicate_pad_numbers_are_jumpers no)
		(fp_circle
			(center 0 0)
			(end 0 0.104648)
			(stroke
				(width 0.1016)
				(type default)
			)
			(fill no)
			(layer "B.SilkS")
		)
		(fp_poly
			(pts
				(xy 0.381 -0.889) (xy 0.381 0.889) (xy -0.381 0.889) (xy -0.381 -0.889)
			)
			(stroke
				(width 0)
				(type default)
			)
			(fill no)
			(layer "B.CrtYd")
		)
		(fp_line
			(start 0.508 -1.016)
			(end 0.254 -1.016)
			(stroke
				(width 0.0254)
				(type default)
			)
			(layer "B.Fab")
		)
		(fp_line
			(start 0.254 -1.016)
			(end -0.508 -1.016)
			(stroke
				(width 0.0254)
				(type default)
			)
			(layer "B.Fab")
		)
		(fp_line
			(start -0.508 -1.016)
			(end -0.508 1.016)
			(stroke
				(width 0.0254)
				(type default)
			)
			(layer "B.Fab")
		)
		(fp_line
			(start 0.508 1.016)
			(end 0.508 -1.016)
			(stroke
				(width 0.0254)
				(type default)
			)
			(layer "B.Fab")
		)
		(fp_line
			(start -0.508 1.016)
			(end 0.508 1.016)
			(stroke
				(width 0.0254)
				(type default)
			)
			(layer "B.Fab")
		)
		(pad "1" smd custom
			(at 0 -0.500126 270)
			(size 0.127 0.127)
			(layers "B.Cu" "B.Mask" "B.Paste")
			(net "VDDAH_SERDES")
			(options
				(clearance outline)
				(anchor circle)
			)
			(primitives
				(gr_poly
					(pts
						(xy -0.1778 0.254) (xy 0.1778 0.254) (xy 0.254 0.1778) (xy 0.254 -0.1778) (xy 0.1778 -0.254) (xy -0.1778 -0.254)
						(xy -0.254 -0.1778) (xy -0.254 0.1778)
					)
					(width 0)
					(fill yes)
				)
			)
		)
		(pad "2" smd custom
			(at 0 0.500126 270)
			(size 0.127 0.127)
			(layers "B.Cu" "B.Mask" "B.Paste")
			(net "GND")
			(options
				(clearance outline)
				(anchor circle)
			)
			(primitives
				(gr_poly
					(pts
						(xy -0.1778 0.254) (xy 0.1778 0.254) (xy 0.254 0.1778) (xy 0.254 -0.1778) (xy 0.1778 -0.254) (xy -0.1778 -0.254)
						(xy -0.254 -0.1778) (xy -0.254 0.1778)
					)
					(width 0)
					(fill yes)
				)
			)
		)
	)
	(footprint ""
		(layer "B.Cu")
		(at 58.674 47.2948 90)
		(property "Reference" "TP36"
			(at -4.0132 -0.53467 270)
			(unlocked yes)
			(layer "B.SilkS")
			(effects
				(font
					(size 0.7874 0.5842)
					(thickness 0.127)
				)
				(justify left mirror)
			)
		)
		(property "Value" "*"
			(at 0.4826 -0.14732 90)
			(unlocked yes)
			(layer "B.Fab")
			(hide yes)
			(effects
				(font
					(size 1.27 0.9652)
					(thickness 0.000001)
				)
				(justify left mirror)
			)
		)
		(property "Device Type" "TP_SMALL"
			(at 0.4826 -0.14732 90)
			(unlocked yes)
			(layer "B.Fab")
			(hide yes)
			(effects
				(font
					(size 1.27 0.9652)
					(thickness 0.000001)
				)
				(justify left mirror)
			)
		)
		(duplicate_pad_numbers_are_jumpers no)
		(fp_line
			(start 0.8636 -0.8636)
			(end 0.8636 0.8636)
			(stroke
				(width 0.1524)
				(type default)
			)
			(layer "B.SilkS")
		)
		(fp_line
			(start -0.8636 -0.8636)
			(end 0.8636 -0.8636)
			(stroke
				(width 0.1524)
				(type default)
			)
			(layer "B.SilkS")
		)
		(fp_line
			(start 0.8636 0.8636)
			(end -0.8636 0.8636)
			(stroke
				(width 0.1524)
				(type default)
			)
			(layer "B.SilkS")
		)
		(fp_line
			(start -0.8636 0.8636)
			(end -0.8636 -0.8636)
			(stroke
				(width 0.1524)
				(type default)
			)
			(layer "B.SilkS")
		)
		(fp_poly
			(pts
				(xy 0.635 -0.635) (xy 0.635 0.635) (xy -0.635 0.635) (xy -0.635 -0.635)
			)
			(stroke
				(width 0)
				(type default)
			)
			(fill no)
			(layer "B.CrtYd")
		)
		(pad "1" smd rect
			(at 0 0 270)
			(size 1.27 1.27)
			(layers "B.Cu" "B.Mask" "B.Paste")
			(net "GL_PHASE1")
		)
	)
	(footprint ""
		(layer "B.Cu")
		(at 20.955 8.128 180)
		(property "Reference" "C85"
			(at 1.04267 -2.159 270)
			(unlocked yes)
			(layer "B.SilkS")
			(effects
				(font
					(size 0.7874 0.5842)
					(thickness 0.127)
				)
				(justify left mirror)
			)
		)
		(property "Value" "0.1UF"
			(at 0.091846 0.2921 90)
			(unlocked yes)
			(layer "B.Fab")
			(hide yes)
			(effects
				(font
					(size 0.7874 0.5842)
					(thickness 0.2032)
				)
				(justify left mirror)
			)
		)
		(property "Device Type" "CAPC0073"
			(at 0.091846 0.2921 90)
			(unlocked yes)
			(layer "B.Fab")
			(hide yes)
			(effects
				(font
					(size 0.7874 0.5842)
					(thickness 0.2032)
				)
				(justify left mirror)
			)
		)
		(duplicate_pad_numbers_are_jumpers no)
		(fp_poly
			(pts
				(xy -0.635 1.0668) (xy -0.635 -1.0668) (xy 0.635 -1.0668) (xy 0.635 1.0668)
			)
			(stroke
				(width 0)
				(type default)
			)
			(fill no)
			(layer "B.CrtYd")
		)
		(fp_line
			(start 0.254 0.508)
			(end 0.254 -0.508)
			(stroke
				(width 0.0254)
				(type default)
			)
			(layer "B.Fab")
		)
		(fp_line
			(start 0.254 -0.508)
			(end -0.254 -0.508)
			(stroke
				(width 0.0254)
				(type default)
			)
			(layer "B.Fab")
		)
		(fp_line
			(start -0.254 0.508)
			(end 0.254 0.508)
			(stroke
				(width 0.0254)
				(type default)
			)
			(layer "B.Fab")
		)
		(fp_line
			(start -0.254 -0.508)
			(end -0.254 0.508)
			(stroke
				(width 0.0254)
				(type default)
			)
			(layer "B.Fab")
		)
		(pad "1" smd rect
			(at 0 -0.4191)
			(size 0.508 0.5334)
			(layers "B.Cu" "B.Mask" "B.Paste")
			(net "VDD_3.3V")
		)
		(pad "2" smd rect
			(at 0 0.4191)
			(size 0.508 0.5334)
			(layers "B.Cu" "B.Mask" "B.Paste")
			(net "GND")
		)
		(zone
			(layer "B.Cu")
			(hatch none 0.5)
			(connect_pads
				(clearance 0)
			)
			(min_thickness 0.25)
			(keepout
				(tracks not_allowed)
				(vias allowed)
				(pads allowed)
				(copperpour not_allowed)
				(footprints allowed)
			)
			(placement
				(enabled no)
				(sheetname "")
			)
			(fill
				(thermal_gap 0.5)
				(thermal_bridge_width 0.5)
				(island_removal_mode 0)
			)
			(polygon
				(pts
					(xy 20.9804 8.1534) (xy 20.9804 8.1026) (xy 20.9296 8.1026) (xy 20.9296 8.1534)
				)
			)
		)
	)
	(footprint ""
		(layer "B.Cu")
		(at 25.146 38.862)
		(property "Reference" "TP38"
			(at -1.143 0.02667 0)
			(unlocked yes)
			(layer "B.SilkS")
			(effects
				(font
					(size 0.7874 0.5842)
					(thickness 0.127)
				)
				(justify left mirror)
			)
		)
		(property "Value" "*"
			(at 0.4826 -0.14732 0)
			(unlocked yes)
			(layer "B.Fab")
			(hide yes)
			(effects
				(font
					(size 1.27 0.9652)
					(thickness 0.000001)
				)
				(justify left mirror)
			)
		)
		(property "Device Type" "TP_SMALL"
			(at 0.4826 -0.14732 0)
			(unlocked yes)
			(layer "B.Fab")
			(hide yes)
			(effects
				(font
					(size 1.27 0.9652)
					(thickness 0.000001)
				)
				(justify left mirror)
			)
		)
		(duplicate_pad_numbers_are_jumpers no)
		(fp_line
			(start -0.8636 -0.8636)
			(end 0.8636 -0.8636)
			(stroke
				(width 0.1524)
				(type default)
			)
			(layer "B.SilkS")
		)
		(fp_line
			(start -0.8636 0.8636)
			(end -0.8636 -0.8636)
			(stroke
				(width 0.1524)
				(type default)
			)
			(layer "B.SilkS")
		)
		(fp_line
			(start 0.8636 -0.8636)
			(end 0.8636 0.8636)
			(stroke
				(width 0.1524)
				(type default)
			)
			(layer "B.SilkS")
		)
		(fp_line
			(start 0.8636 0.8636)
			(end -0.8636 0.8636)
			(stroke
				(width 0.1524)
				(type default)
			)
			(layer "B.SilkS")
		)
		(fp_poly
			(pts
				(xy 0.635 -0.635) (xy 0.635 0.635) (xy -0.635 0.635) (xy -0.635 -0.635)
			)
			(stroke
				(width 0)
				(type default)
			)
			(fill no)
			(layer "B.CrtYd")
		)
		(pad "1" smd rect
			(at 0 0 180)
			(size 1.27 1.27)
			(layers "B.Cu" "B.Mask" "B.Paste")
			(net "NFP_VDD_CORE_IMON")
		)
	)
	(footprint ""
		(layer "B.Cu")
		(at 60.236989 7.542022 180)
		(property "Reference" "C169"
			(at 0 0 0)
			(layer "B.SilkS")
			(hide yes)
			(effects
				(font
					(size 1.27 1.27)
				)
				(justify mirror)
			)
		)
		(property "Value" ""
			(at 0 0 0)
			(layer "B.Fab")
			(effects
				(font
					(size 1.27 1.27)
				)
				(justify mirror)
			)
		)
		(duplicate_pad_numbers_are_jumpers no)
		(fp_circle
			(center 0 0)
			(end -0.104648 0)
			(stroke
				(width 0.1016)
				(type default)
			)
			(fill no)
			(layer "B.SilkS")
		)
		(fp_poly
			(pts
				(xy 0.381 -0.889) (xy 0.381 0.889) (xy -0.381 0.889) (xy -0.381 -0.889)
			)
			(stroke
				(width 0)
				(type default)
			)
			(fill no)
			(layer "B.CrtYd")
		)
		(fp_line
			(start 0.508 1.016)
			(end 0.508 -1.016)
			(stroke
				(width 0.0254)
				(type default)
			)
			(layer "B.Fab")
		)
		(fp_line
			(start 0.508 -1.016)
			(end 0.254 -1.016)
			(stroke
				(width 0.0254)
				(type default)
			)
			(layer "B.Fab")
		)
		(fp_line
			(start 0.254 -1.016)
			(end -0.508 -1.016)
			(stroke
				(width 0.0254)
				(type default)
			)
			(layer "B.Fab")
		)
		(fp_line
			(start -0.508 1.016)
			(end 0.508 1.016)
			(stroke
				(width 0.0254)
				(type default)
			)
			(layer "B.Fab")
		)
		(fp_line
			(start -0.508 -1.016)
			(end -0.508 1.016)
			(stroke
				(width 0.0254)
				(type default)
			)
			(layer "B.Fab")
		)
		(pad "1" smd custom
			(at 0 -0.500126)
			(size 0.127 0.127)
			(layers "B.Cu" "B.Mask" "B.Paste")
			(net "VDDA_PCIE0")
			(options
				(clearance outline)
				(anchor circle)
			)
			(primitives
				(gr_poly
					(pts
						(xy -0.1778 0.254) (xy 0.1778 0.254) (xy 0.254 0.1778) (xy 0.254 -0.1778) (xy 0.1778 -0.254) (xy -0.1778 -0.254)
						(xy -0.254 -0.1778) (xy -0.254 0.1778)
					)
					(width 0)
					(fill yes)
				)
			)
		)
		(pad "2" smd custom
			(at 0 0.500126)
			(size 0.127 0.127)
			(layers "B.Cu" "B.Mask" "B.Paste")
			(net "GND")
			(options
				(clearance outline)
				(anchor circle)
			)
			(primitives
				(gr_poly
					(pts
						(xy -0.1778 0.254) (xy 0.1778 0.254) (xy 0.254 0.1778) (xy 0.254 -0.1778) (xy 0.1778 -0.254) (xy -0.1778 -0.254)
						(xy -0.254 -0.1778) (xy -0.254 0.1778)
					)
					(width 0)
					(fill yes)
				)
			)
		)
	)
	(footprint ""
		(layer "B.Cu")
		(at 81.050994 2.699004)
		(property "Reference" "V1_A-BA2"
			(at 0 0 0)
			(layer "B.SilkS")
			(hide yes)
			(effects
				(font
					(size 1.27 1.27)
				)
				(justify mirror)
			)
		)
		(property "Value" ""
			(at 0 0 0)
			(layer "B.Fab")
			(effects
				(font
					(size 1.27 1.27)
				)
				(justify mirror)
			)
		)
		(duplicate_pad_numbers_are_jumpers no)
		(pad "1" thru_hole circle
			(at 0 0 180)
			(size 0.4572 0.4572)
			(drill 0.20574)
			(layers "*.Cu" "*.Mask")
			(remove_unused_layers no)
			(net "DDR0_32A_BA2")
			(clearance 0.1143)
			(thermal_gap 0.1143)
		)
	)
	(footprint ""
		(layer "B.Cu")
		(at 47.736887 31.041975 -90)
		(property "Reference" "C176"
			(at 0 0 90)
			(layer "B.SilkS")
			(hide yes)
			(effects
				(font
					(size 1.27 1.27)
				)
				(justify mirror)
			)
		)
		(property "Value" ""
			(at 0 0 90)
			(layer "B.Fab")
			(effects
				(font
					(size 1.27 1.27)
				)
				(justify mirror)
			)
		)
		(duplicate_pad_numbers_are_jumpers no)
		(fp_circle
			(center 0 0)
			(end 0 -0.104648)
			(stroke
				(width 0.1016)
				(type default)
			)
			(fill no)
			(layer "B.SilkS")
		)
		(fp_poly
			(pts
				(xy 0.381 -0.889) (xy 0.381 0.889) (xy -0.381 0.889) (xy -0.381 -0.889)
			)
			(stroke
				(width 0)
				(type default)
			)
			(fill no)
			(layer "B.CrtYd")
		)
		(fp_line
			(start -0.508 1.016)
			(end 0.508 1.016)
			(stroke
				(width 0.0254)
				(type default)
			)
			(layer "B.Fab")
		)
		(fp_line
			(start 0.508 1.016)
			(end 0.508 -1.016)
			(stroke
				(width 0.0254)
				(type default)
			)
			(layer "B.Fab")
		)
		(fp_line
			(start -0.508 -1.016)
			(end -0.508 1.016)
			(stroke
				(width 0.0254)
				(type default)
			)
			(layer "B.Fab")
		)
		(fp_line
			(start 0.254 -1.016)
			(end -0.508 -1.016)
			(stroke
				(width 0.0254)
				(type default)
			)
			(layer "B.Fab")
		)
		(fp_line
			(start 0.508 -1.016)
			(end 0.254 -1.016)
			(stroke
				(width 0.0254)
				(type default)
			)
			(layer "B.Fab")
		)
		(pad "1" smd custom
			(at 0 -0.500126 90)
			(size 0.127 0.127)
			(layers "B.Cu" "B.Mask" "B.Paste")
			(net "VDD_CORE")
			(options
				(clearance outline)
				(anchor circle)
			)
			(primitives
				(gr_poly
					(pts
						(xy -0.1778 0.254) (xy 0.1778 0.254) (xy 0.254 0.1778) (xy 0.254 -0.1778) (xy 0.1778 -0.254) (xy -0.1778 -0.254)
						(xy -0.254 -0.1778) (xy -0.254 0.1778)
					)
					(width 0)
					(fill yes)
				)
			)
		)
		(pad "2" smd custom
			(at 0 0.500126 90)
			(size 0.127 0.127)
			(layers "B.Cu" "B.Mask" "B.Paste")
			(net "GND")
			(options
				(clearance outline)
				(anchor circle)
			)
			(primitives
				(gr_poly
					(pts
						(xy -0.1778 0.254) (xy 0.1778 0.254) (xy 0.254 0.1778) (xy 0.254 -0.1778) (xy 0.1778 -0.254) (xy -0.1778 -0.254)
						(xy -0.254 -0.1778) (xy -0.254 0.1778)
					)
					(width 0)
					(fill yes)
				)
			)
		)
	)
	(footprint ""
		(layer "B.Cu")
		(at 2.667 17.4498)
		(property "Reference" "R377"
			(at -0.78867 3.1242 270)
			(unlocked yes)
			(layer "B.SilkS")
			(effects
				(font
					(size 0.7874 0.5842)
					(thickness 0.127)
				)
				(justify left mirror)
			)
		)
		(property "Value" "4.75K"
			(at 0.148158 1.3462 270)
			(unlocked yes)
			(layer "B.Fab")
			(hide yes)
			(effects
				(font
					(size 1.27 0.9652)
					(thickness 0.000001)
				)
				(justify left mirror)
			)
		)
		(property "Device Type" "REST4024"
			(at 0.148158 1.3462 270)
			(unlocked yes)
			(layer "B.Fab")
			(hide yes)
			(effects
				(font
					(size 1.27 0.9652)
					(thickness 0.000001)
				)
				(justify left mirror)
			)
		)
		(duplicate_pad_numbers_are_jumpers no)
		(fp_poly
			(pts
				(xy -0.635 1.0668) (xy -0.635 -1.0668) (xy 0.635 -1.0668) (xy 0.635 1.0668)
			)
			(stroke
				(width 0)
				(type default)
			)
			(fill no)
			(layer "B.CrtYd")
		)
		(fp_line
			(start -0.254 -0.508)
			(end -0.254 0.508)
			(stroke
				(width 0.0254)
				(type default)
			)
			(layer "B.Fab")
		)
		(fp_line
			(start -0.254 0.508)
			(end 0.254 0.508)
			(stroke
				(width 0.0254)
				(type default)
			)
			(layer "B.Fab")
		)
		(fp_line
			(start 0.254 -0.508)
			(end -0.254 -0.508)
			(stroke
				(width 0.0254)
				(type default)
			)
			(layer "B.Fab")
		)
		(fp_line
			(start 0.254 0.508)
			(end 0.254 -0.508)
			(stroke
				(width 0.0254)
				(type default)
			)
			(layer "B.Fab")
		)
		(pad "1" smd rect
			(at 0 -0.4191 180)
			(size 0.508 0.5334)
			(layers "B.Cu" "B.Mask" "B.Paste")
			(net "NWK0_I2C_SCL")
		)
		(pad "2" smd rect
			(at 0 0.4191 180)
			(size 0.508 0.5334)
			(layers "B.Cu" "B.Mask" "B.Paste")
			(net "EXT_3.3V")
		)
		(zone
			(layer "B.Cu")
			(hatch none 0.5)
			(connect_pads
				(clearance 0)
			)
			(min_thickness 0.25)
			(keepout
				(tracks not_allowed)
				(vias allowed)
				(pads allowed)
				(copperpour not_allowed)
				(footprints allowed)
			)
			(placement
				(enabled no)
				(sheetname "")
			)
			(fill
				(thermal_gap 0.5)
				(thermal_bridge_width 0.5)
				(island_removal_mode 0)
			)
			(polygon
				(pts
					(xy 2.6416 17.4244) (xy 2.6416 17.4752) (xy 2.6924 17.4752) (xy 2.6924 17.4244)
				)
			)
		)
	)
	(footprint ""
		(layer "B.Cu")
		(at 5.2578 9.7028)
		(property "Reference" "TP28"
			(at 1.82753 1.9812 270)
			(unlocked yes)
			(layer "B.SilkS")
			(effects
				(font
					(size 0.7874 0.5842)
					(thickness 0.127)
				)
				(justify left mirror)
			)
		)
		(property "Value" "*"
			(at 0.4826 -0.14732 0)
			(unlocked yes)
			(layer "B.Fab")
			(hide yes)
			(effects
				(font
					(size 1.27 0.9652)
					(thickness 0.000001)
				)
				(justify left mirror)
			)
		)
		(property "Device Type" "TP_SMALL"
			(at 0.4826 -0.14732 0)
			(unlocked yes)
			(layer "B.Fab")
			(hide yes)
			(effects
				(font
					(size 1.27 0.9652)
					(thickness 0.000001)
				)
				(justify left mirror)
			)
		)
		(duplicate_pad_numbers_are_jumpers no)
		(fp_line
			(start -0.8636 -0.8636)
			(end 0.8636 -0.8636)
			(stroke
				(width 0.1524)
				(type default)
			)
			(layer "B.SilkS")
		)
		(fp_line
			(start -0.8636 0.8636)
			(end -0.8636 -0.8636)
			(stroke
				(width 0.1524)
				(type default)
			)
			(layer "B.SilkS")
		)
		(fp_line
			(start 0.8636 -0.8636)
			(end 0.8636 0.8636)
			(stroke
				(width 0.1524)
				(type default)
			)
			(layer "B.SilkS")
		)
		(fp_line
			(start 0.8636 0.8636)
			(end -0.8636 0.8636)
			(stroke
				(width 0.1524)
				(type default)
			)
			(layer "B.SilkS")
		)
		(fp_poly
			(pts
				(xy 0.635 -0.635) (xy 0.635 0.635) (xy -0.635 0.635) (xy -0.635 -0.635)
			)
			(stroke
				(width 0)
				(type default)
			)
			(fill no)
			(layer "B.CrtYd")
		)
		(pad "1" smd rect
			(at 0 0 180)
			(size 1.27 1.27)
			(layers "B.Cu" "B.Mask" "B.Paste")
			(net "PGRM_JTAG_TDI")
		)
	)
)
